(kicad_pcb
	(version 20260206)
	(generator "pcbnew")
	(generator_version "10.0")
	(general
		(thickness 1.6)
		(legacy_teardrops no)
	)
	(paper "A4")
	(title_block
		(title "03242023_DA0F0TMBIJ0_F0T_Motherboard_J_brd_V01_OCP.brd")
		(comment 1 "Grand Teton / footprints 1026-1029 of 6105")
	)
	(layers
		(0 "F.Cu" signal "TOP")
		(4 "In1.Cu" signal "GND")
		(6 "In2.Cu" signal "IN1")
		(8 "In3.Cu" signal "GND1")
		(10 "In4.Cu" signal "IN2")
		(12 "In5.Cu" signal "GND2")
		(14 "In6.Cu" signal "IN3")
		(16 "In7.Cu" signal "GND3")
		(18 "In8.Cu" signal "VCC")
		(20 "In9.Cu" signal "VCC1")
		(22 "In10.Cu" signal "GND4")
		(24 "In11.Cu" signal "IN4")
		(26 "In12.Cu" signal "GND5")
		(28 "In13.Cu" signal "IN5")
		(30 "In14.Cu" signal "GND6")
		(32 "In15.Cu" signal "IN6")
		(34 "In16.Cu" signal "GND7")
		(2 "B.Cu" signal "BOTTOM")
		(9 "F.Adhes" user "F.Adhesive")
		(11 "B.Adhes" user "B.Adhesive")
		(13 "F.Paste" user "Package Geometry/Pastemask Top")
		(15 "B.Paste" user "Package Geometry/Pastemask Bottom")
		(5 "F.SilkS" user "Ref Des/Silkscreen Top")
		(7 "B.SilkS" user "Ref Des/Silkscreen Bottom")
		(1 "F.Mask" user "Board Geometry/Soldermask Top")
		(3 "B.Mask" user "Board Geometry/Soldermask Bottom")
		(17 "Dwgs.User" user "User.Drawings")
		(19 "Cmts.User" user "User.Comments")
		(21 "Eco1.User" user "User.Eco1")
		(23 "Eco2.User" user "User.Eco2")
		(25 "Edge.Cuts" user "Board Geometry/Outline")
		(27 "Margin" user)
		(31 "F.CrtYd" user "Package Geometry/Place Bound Top")
		(29 "B.CrtYd" user "Package Geometry/Place Bound Bottom")
		(35 "F.Fab" user "Ref Des/Assembly Top")
		(33 "B.Fab" user "Ref Des/Assembly Bottom")
	)
	(footprint ""
		(layer "F.Cu")
		(at 366.3696 -405.9936 180)
		(property "Reference" "C2374"
			(at 0 0 180)
			(layer "F.SilkS")
			(hide yes)
			(effects
				(font
					(size 1.27 1.27)
				)
			)
		)
		(property "Value" ""
			(at 0 0 180)
			(layer "F.Fab")
			(effects
				(font
					(size 1.27 1.27)
				)
			)
		)
		(duplicate_pad_numbers_are_jumpers no)
		(fp_line
			(start 0.7874 0.4064)
			(end -0.7874 0.4064)
			(stroke
				(width 0.1524)
				(type default)
			)
			(layer "F.SilkS")
		)
		(fp_line
			(start 0.7874 -0.4064)
			(end 0.7874 0.4064)
			(stroke
				(width 0.1524)
				(type default)
			)
			(layer "F.SilkS")
		)
		(fp_line
			(start -0.7874 0.4064)
			(end -0.7874 -0.4064)
			(stroke
				(width 0.1524)
				(type default)
			)
			(layer "F.SilkS")
		)
		(fp_line
			(start -0.7874 -0.4064)
			(end 0.7874 -0.4064)
			(stroke
				(width 0.1524)
				(type default)
			)
			(layer "F.SilkS")
		)
		(fp_line
			(start 0.67945 0.3048)
			(end 0.120396 0.3048)
			(stroke
				(width 0.1)
				(type default)
			)
			(layer "F.Fab")
		)
		(fp_line
			(start 0.67945 -0.3048)
			(end 0.67945 0.3048)
			(stroke
				(width 0.1)
				(type default)
			)
			(layer "F.Fab")
		)
		(fp_line
			(start 0.12065 -0.2794)
			(end 0.12065 -0.3048)
			(stroke
				(width 0.1)
				(type default)
			)
			(layer "F.Fab")
		)
		(fp_line
			(start 0.12065 -0.3048)
			(end 0.67945 -0.3048)
			(stroke
				(width 0.1)
				(type default)
			)
			(layer "F.Fab")
		)
		(fp_line
			(start 0.120396 0.3048)
			(end 0.120396 0.2794)
			(stroke
				(width 0.1)
				(type default)
			)
			(layer "F.Fab")
		)
		(fp_line
			(start 0.120396 0.2794)
			(end -0.12065 0.2794)
			(stroke
				(width 0.1)
				(type default)
			)
			(layer "F.Fab")
		)
		(fp_line
			(start -0.12065 0.3048)
			(end -0.67945 0.3048)
			(stroke
				(width 0.1)
				(type default)
			)
			(layer "F.Fab")
		)
		(fp_line
			(start -0.12065 0.2794)
			(end -0.12065 0.3048)
			(stroke
				(width 0.1)
				(type default)
			)
			(layer "F.Fab")
		)
		(fp_line
			(start -0.12065 -0.2794)
			(end 0.12065 -0.2794)
			(stroke
				(width 0.1)
				(type default)
			)
			(layer "F.Fab")
		)
		(fp_line
			(start -0.12065 -0.305054)
			(end -0.12065 -0.2794)
			(stroke
				(width 0.1)
				(type default)
			)
			(layer "F.Fab")
		)
		(fp_line
			(start -0.67945 0.3048)
			(end -0.67945 -0.305054)
			(stroke
				(width 0.1)
				(type default)
			)
			(layer "F.Fab")
		)
		(fp_line
			(start -0.67945 -0.305054)
			(end -0.12065 -0.305054)
			(stroke
				(width 0.1)
				(type default)
			)
			(layer "F.Fab")
		)
		(pad "1" smd circle
			(at -0.40005 0 180)
			(size 0 0)
			(layers "F.Cu" "F.Mask" "F.Paste")
			(net "PRSNT_CABLE_SWB_B1_ISO_N")
		)
		(pad "2" smd circle
			(at 0.40005 0 180)
			(size 0 0)
			(layers "F.Cu" "F.Mask" "F.Paste")
			(net "GND")
		)
	)
	(footprint ""
		(layer "F.Cu")
		(at 274.436078 -420.1033 180)
		(property "Reference" "U329"
			(at 2.276856 -2.56921 0)
			(unlocked yes)
			(layer "F.SilkS")
			(effects
				(font
					(size 0.7874 0.5842)
					(thickness 0.1524)
				)
				(justify left)
			)
		)
		(property "Value" ""
			(at 0 0 180)
			(layer "F.Fab")
			(effects
				(font
					(size 1.27 1.27)
				)
			)
		)
		(duplicate_pad_numbers_are_jumpers no)
		(fp_line
			(start 1.603248 1.500124)
			(end -1.603248 1.500124)
			(stroke
				(width 0.1524)
				(type default)
			)
			(layer "F.SilkS")
		)
		(fp_line
			(start 1.603248 -1.500124)
			(end 1.603248 1.500124)
			(stroke
				(width 0.1524)
				(type default)
			)
			(layer "F.SilkS")
		)
		(fp_line
			(start -1.603248 1.500124)
			(end -1.603248 -1.500124)
			(stroke
				(width 0.1524)
				(type default)
			)
			(layer "F.SilkS")
		)
		(fp_line
			(start -1.603248 -1.500124)
			(end 1.603248 -1.500124)
			(stroke
				(width 0.1524)
				(type default)
			)
			(layer "F.SilkS")
		)
		(fp_line
			(start 1.249934 0.219964)
			(end 1.249934 -0.219964)
			(stroke
				(width 0.1)
				(type default)
			)
			(layer "F.Fab")
		)
		(fp_line
			(start 1.249934 -0.219964)
			(end 0.700024 -0.219964)
			(stroke
				(width 0.1)
				(type default)
			)
			(layer "F.Fab")
		)
		(fp_line
			(start 0.700024 1.500124)
			(end 0.700024 0.219964)
			(stroke
				(width 0.1)
				(type default)
			)
			(layer "F.Fab")
		)
		(fp_line
			(start 0.700024 0.219964)
			(end 1.249934 0.219964)
			(stroke
				(width 0.1)
				(type default)
			)
			(layer "F.Fab")
		)
		(fp_line
			(start 0.700024 -0.219964)
			(end 0.700024 -1.500124)
			(stroke
				(width 0.1)
				(type default)
			)
			(layer "F.Fab")
		)
		(fp_line
			(start 0.700024 -1.500124)
			(end -0.700024 -1.500124)
			(stroke
				(width 0.1)
				(type default)
			)
			(layer "F.Fab")
		)
		(fp_line
			(start -0.6985 0.729996)
			(end -1.249934 0.729996)
			(stroke
				(width 0.1)
				(type default)
			)
			(layer "F.Fab")
		)
		(fp_line
			(start -0.6985 -0.729996)
			(end -0.6985 0.729996)
			(stroke
				(width 0.1)
				(type default)
			)
			(layer "F.Fab")
		)
		(fp_line
			(start -0.700024 1.500124)
			(end 0.700024 1.500124)
			(stroke
				(width 0.1)
				(type default)
			)
			(layer "F.Fab")
		)
		(fp_line
			(start -0.700024 1.169924)
			(end -0.700024 1.500124)
			(stroke
				(width 0.1)
				(type default)
			)
			(layer "F.Fab")
		)
		(fp_line
			(start -0.700024 -1.169924)
			(end -1.249934 -1.169924)
			(stroke
				(width 0.1)
				(type default)
			)
			(layer "F.Fab")
		)
		(fp_line
			(start -0.700024 -1.500124)
			(end -0.700024 -1.169924)
			(stroke
				(width 0.1)
				(type default)
			)
			(layer "F.Fab")
		)
		(fp_line
			(start -1.249934 1.169924)
			(end -0.700024 1.169924)
			(stroke
				(width 0.1)
				(type default)
			)
			(layer "F.Fab")
		)
		(fp_line
			(start -1.249934 0.729996)
			(end -1.249934 1.169924)
			(stroke
				(width 0.1)
				(type default)
			)
			(layer "F.Fab")
		)
		(fp_line
			(start -1.249934 -0.729996)
			(end -0.6985 -0.729996)
			(stroke
				(width 0.1)
				(type default)
			)
			(layer "F.Fab")
		)
		(fp_line
			(start -1.249934 -1.169924)
			(end -1.249934 -0.729996)
			(stroke
				(width 0.1)
				(type default)
			)
			(layer "F.Fab")
		)
		(fp_rect
			(start -0.700024 1.500124)
			(end 0.700024 -1.500124)
			(stroke
				(width 0)
				(type default)
			)
			(fill no)
			(layer "F.Fab")
		)
		(pad "D" smd rect
			(at 0.999998 0 90)
			(size 0.8128 0.9144)
			(layers "F.Cu" "F.Mask" "F.Paste")
			(net "A_HSC_LOW_DRAIN")
		)
		(pad "G" smd rect
			(at -0.999998 -0.94996 90)
			(size 0.8128 0.9144)
			(layers "F.Cu" "F.Mask" "F.Paste")
			(net "A_HSC_LOW_GATE")
		)
		(pad "S" smd rect
			(at -0.999998 0.94996 90)
			(size 0.8128 0.9144)
			(layers "F.Cu" "F.Mask" "F.Paste")
			(net "GND")
		)
	)
	(footprint ""
		(layer "F.Cu")
		(at 282.452826 -18.491962 180)
		(property "Reference" "R3183"
			(at 0 0 180)
			(layer "F.SilkS")
			(hide yes)
			(effects
				(font
					(size 1.27 1.27)
				)
			)
		)
		(property "Value" ""
			(at 0 0 180)
			(layer "F.Fab")
			(effects
				(font
					(size 1.27 1.27)
				)
			)
		)
		(duplicate_pad_numbers_are_jumpers no)
		(fp_line
			(start 0.7874 0.4064)
			(end -0.7874 0.4064)
			(stroke
				(width 0.1524)
				(type default)
			)
			(layer "F.SilkS")
		)
		(fp_line
			(start 0.7874 -0.4064)
			(end 0.7874 0.4064)
			(stroke
				(width 0.1524)
				(type default)
			)
			(layer "F.SilkS")
		)
		(fp_line
			(start -0.7874 0.4064)
			(end -0.7874 -0.4064)
			(stroke
				(width 0.1524)
				(type default)
			)
			(layer "F.SilkS")
		)
		(fp_line
			(start -0.7874 -0.4064)
			(end 0.7874 -0.4064)
			(stroke
				(width 0.1524)
				(type default)
			)
			(layer "F.SilkS")
		)
		(fp_line
			(start 0.67945 0.3048)
			(end 0.120396 0.3048)
			(stroke
				(width 0.1)
				(type default)
			)
			(layer "F.Fab")
		)
		(fp_line
			(start 0.67945 -0.3048)
			(end 0.67945 0.3048)
			(stroke
				(width 0.1)
				(type default)
			)
			(layer "F.Fab")
		)
		(fp_line
			(start 0.12065 -0.2794)
			(end 0.12065 -0.3048)
			(stroke
				(width 0.1)
				(type default)
			)
			(layer "F.Fab")
		)
		(fp_line
			(start 0.12065 -0.3048)
			(end 0.67945 -0.3048)
			(stroke
				(width 0.1)
				(type default)
			)
			(layer "F.Fab")
		)
		(fp_line
			(start 0.120396 0.3048)
			(end 0.120396 0.2794)
			(stroke
				(width 0.1)
				(type default)
			)
			(layer "F.Fab")
		)
		(fp_line
			(start 0.120396 0.2794)
			(end -0.12065 0.2794)
			(stroke
				(width 0.1)
				(type default)
			)
			(layer "F.Fab")
		)
		(fp_line
			(start -0.12065 0.3048)
			(end -0.67945 0.3048)
			(stroke
				(width 0.1)
				(type default)
			)
			(layer "F.Fab")
		)
		(fp_line
			(start -0.12065 0.2794)
			(end -0.12065 0.3048)
			(stroke
				(width 0.1)
				(type default)
			)
			(layer "F.Fab")
		)
		(fp_line
			(start -0.12065 -0.2794)
			(end 0.12065 -0.2794)
			(stroke
				(width 0.1)
				(type default)
			)
			(layer "F.Fab")
		)
		(fp_line
			(start -0.12065 -0.305054)
			(end -0.12065 -0.2794)
			(stroke
				(width 0.1)
				(type default)
			)
			(layer "F.Fab")
		)
		(fp_line
			(start -0.67945 0.3048)
			(end -0.67945 -0.305054)
			(stroke
				(width 0.1)
				(type default)
			)
			(layer "F.Fab")
		)
		(fp_line
			(start -0.67945 -0.305054)
			(end -0.12065 -0.305054)
			(stroke
				(width 0.1)
				(type default)
			)
			(layer "F.Fab")
		)
		(pad "1" smd circle
			(at -0.40005 0 180)
			(size 0 0)
			(layers "F.Cu" "F.Mask" "F.Paste")
			(net "P3V3_OCP_V3_2")
		)
		(pad "2" smd circle
			(at 0.40005 0 180)
			(size 0 0)
			(layers "F.Cu" "F.Mask" "F.Paste")
			(net "PU_OCP_V3_2_WAKE_OE")
		)
	)
	(footprint ""
		(layer "F.Cu")
		(at 301.45482 -421.41521 90)
		(property "Reference" "R4129"
			(at 0 0 90)
			(layer "F.SilkS")
			(hide yes)
			(effects
				(font
					(size 1.27 1.27)
				)
			)
		)
		(property "Value" ""
			(at 0 0 90)
			(layer "F.Fab")
			(effects
				(font
					(size 1.27 1.27)
				)
			)
		)
		(duplicate_pad_numbers_are_jumpers no)
		(fp_line
			(start 0.7874 -0.4064)
			(end 0.7874 0.4064)
			(stroke
				(width 0.1524)
				(type default)
			)
			(layer "F.SilkS")
		)
		(fp_line
			(start -0.7874 -0.4064)
			(end 0.7874 -0.4064)
			(stroke
				(width 0.1524)
				(type default)
			)
			(layer "F.SilkS")
		)
		(fp_line
			(start 0.7874 0.4064)
			(end -0.7874 0.4064)
			(stroke
				(width 0.1524)
				(type default)
			)
			(layer "F.SilkS")
		)
		(fp_line
			(start -0.7874 0.4064)
			(end -0.7874 -0.4064)
			(stroke
				(width 0.1524)
				(type default)
			)
			(layer "F.SilkS")
		)
		(fp_line
			(start -0.12065 -0.305054)
			(end -0.12065 -0.2794)
			(stroke
				(width 0.1)
				(type default)
			)
			(layer "F.Fab")
		)
		(fp_line
			(start -0.67945 -0.305054)
			(end -0.12065 -0.305054)
			(stroke
				(width 0.1)
				(type default)
			)
			(layer "F.Fab")
		)
		(fp_line
			(start 0.67945 -0.3048)
			(end 0.67945 0.3048)
			(stroke
				(width 0.1)
				(type default)
			)
			(layer "F.Fab")
		)
		(fp_line
			(start 0.12065 -0.3048)
			(end 0.67945 -0.3048)
			(stroke
				(width 0.1)
				(type default)
			)
			(layer "F.Fab")
		)
		(fp_line
			(start 0.12065 -0.2794)
			(end 0.12065 -0.3048)
			(stroke
				(width 0.1)
				(type default)
			)
			(layer "F.Fab")
		)
		(fp_line
			(start -0.12065 -0.2794)
			(end 0.12065 -0.2794)
			(stroke
				(width 0.1)
				(type default)
			)
			(layer "F.Fab")
		)
		(fp_line
			(start 0.120396 0.2794)
			(end -0.12065 0.2794)
			(stroke
				(width 0.1)
				(type default)
			)
			(layer "F.Fab")
		)
		(fp_line
			(start -0.12065 0.2794)
			(end -0.12065 0.3048)
			(stroke
				(width 0.1)
				(type default)
			)
			(layer "F.Fab")
		)
		(fp_line
			(start 0.67945 0.3048)
			(end 0.120396 0.3048)
			(stroke
				(width 0.1)
				(type default)
			)
			(layer "F.Fab")
		)
		(fp_line
			(start 0.120396 0.3048)
			(end 0.120396 0.2794)
			(stroke
				(width 0.1)
				(type default)
			)
			(layer "F.Fab")
		)
		(fp_line
			(start -0.12065 0.3048)
			(end -0.67945 0.3048)
			(stroke
				(width 0.1)
				(type default)
			)
			(layer "F.Fab")
		)
		(fp_line
			(start -0.67945 0.3048)
			(end -0.67945 -0.305054)
			(stroke
				(width 0.1)
				(type default)
			)
			(layer "F.Fab")
		)
		(pad "1" smd circle
			(at -0.40005 0 90)
			(size 0 0)
			(layers "F.Cu" "F.Mask" "F.Paste")
			(net "P3V3_AUX")
		)
		(pad "2" smd circle
			(at 0.40005 0 90)
			(size 0 0)
			(layers "F.Cu" "F.Mask" "F.Paste")
			(net "PRSNT_CABLE_GPU_B3_ISO_N")
		)
	)
)
